# T6G (Grand Teton) — schematic netlist excerpt (pin names and nets, part order shuffled) for the footprints in the layout excerpt that follows; sources: Cadence DE-HDL packaged netlist, KiCad conversion of 04192023_DAF0TMB3IC0_F0TG_MB_C_brd_V02_OCP.brd

C2270  Q_CAP  22UF 4V 20% X6S  pkg C0402  page 72 : A = PVDDIO_P1 ; B = GND
C920  Q_CAP_DIFFBUS  DIFF BUS_0.22UF 6.3V 20% X6S  pkg C0201  page 63 : \1\ = P5E_CPU0_P0_TX_C_DN<6> ; \2\ = P5E_CPU0_P0_TX_DN<6>
R961  Q_RES  0 5% EMPTY  pkg 0603LF  page 279 : A = P0V9_CPU0_RT_2D ; B = P0V9_CPU0_RT0_2A_2D

(kicad_pcb
	(version 20260206)
	(generator "pcbnew")
	(generator_version "10.0")
	(general
		(thickness 1.6)
		(legacy_teardrops no)
	)
	(paper "A4")
	(title_block
		(title "04192023_DAF0TMB3IC0_F0TG_MB_C_brd_V02_OCP.brd")
		(comment 1 "Grand Teton / footprints 467-469 of 8354")
	)
	(layers
		(0 "F.Cu" signal "TOP")
		(4 "In1.Cu" signal "GND")
		(6 "In2.Cu" signal "IN1")
		(8 "In3.Cu" signal "GND1")
		(10 "In4.Cu" signal "IN2")
		(12 "In5.Cu" signal "GND2")
		(14 "In6.Cu" signal "IN3")
		(16 "In7.Cu" signal "GND3")
		(18 "In8.Cu" signal "VCC")
		(20 "In9.Cu" signal "VCC1")
		(22 "In10.Cu" signal "GND4")
		(24 "In11.Cu" signal "IN4")
		(26 "In12.Cu" signal "GND5")
		(28 "In13.Cu" signal "IN5")
		(30 "In14.Cu" signal "GND6")
		(32 "In15.Cu" signal "IN6")
		(34 "In16.Cu" signal "GND7")
		(2 "B.Cu" signal "BOTTOM")
		(9 "F.Adhes" user "F.Adhesive")
		(11 "B.Adhes" user "B.Adhesive")
		(13 "F.Paste" user "Package Geometry/Pastemask Top")
		(15 "B.Paste" user "Package Geometry/Pastemask Bottom")
		(5 "F.SilkS" user "Ref Des/Silkscreen Top")
		(7 "B.SilkS" user "Ref Des/Silkscreen Bottom")
		(1 "F.Mask" user "Board Geometry/Soldermask Top")
		(3 "B.Mask" user "Board Geometry/Soldermask Bottom")
		(17 "Dwgs.User" user "User.Drawings")
		(19 "Cmts.User" user "User.Comments")
		(21 "Eco1.User" user "User.Eco1")
		(23 "Eco2.User" user "User.Eco2")
		(25 "Edge.Cuts" user "Board Geometry/Outline")
		(27 "Margin" user)
		(31 "F.CrtYd" user "Package Geometry/Place Bound Top")
		(29 "B.CrtYd" user "Package Geometry/Place Bound Bottom")
		(35 "F.Fab" user "Ref Des/Assembly Top")
		(33 "B.Fab" user "Ref Des/Assembly Bottom")
	)
	(footprint ""
		(layer "F.Cu")
		(at 300.62297 -407.79446)
		(property "Reference" "R961"
			(at 0 0 0)
			(layer "F.SilkS")
			(hide yes)
			(effects
				(font
					(size 1.27 1.27)
				)
			)
		)
		(property "Value" ""
			(at 0 0 0)
			(layer "F.Fab")
			(effects
				(font
					(size 1.27 1.27)
				)
			)
		)
		(duplicate_pad_numbers_are_jumpers no)
		(fp_line
			(start -1.2954 -0.5842)
			(end 1.2954 -0.5842)
			(stroke
				(width 0.1524)
				(type default)
			)
			(layer "F.SilkS")
		)
		(fp_line
			(start -1.2954 0.5842)
			(end -1.2954 -0.5842)
			(stroke
				(width 0.1524)
				(type default)
			)
			(layer "F.SilkS")
		)
		(fp_line
			(start 1.2954 -0.5842)
			(end 1.2954 0.5842)
			(stroke
				(width 0.1524)
				(type default)
			)
			(layer "F.SilkS")
		)
		(fp_line
			(start 1.2954 0.5842)
			(end -1.2954 0.5842)
			(stroke
				(width 0.1524)
				(type default)
			)
			(layer "F.SilkS")
		)
		(fp_line
			(start -1.1938 -0.406654)
			(end -0.8636 -0.406654)
			(stroke
				(width 0.1)
				(type default)
			)
			(layer "F.Fab")
		)
		(fp_line
			(start -1.1938 0.4064)
			(end -1.1938 -0.406654)
			(stroke
				(width 0.1)
				(type default)
			)
			(layer "F.Fab")
		)
		(fp_line
			(start -0.8636 -0.4572)
			(end 0.8636 -0.4572)
			(stroke
				(width 0.1)
				(type default)
			)
			(layer "F.Fab")
		)
		(fp_line
			(start -0.8636 -0.406654)
			(end -0.8636 -0.4572)
			(stroke
				(width 0.1)
				(type default)
			)
			(layer "F.Fab")
		)
		(fp_line
			(start -0.8636 0.4064)
			(end -1.1938 0.4064)
			(stroke
				(width 0.1)
				(type default)
			)
			(layer "F.Fab")
		)
		(fp_line
			(start -0.8636 0.4318)
			(end -0.8636 0.4064)
			(stroke
				(width 0.1)
				(type default)
			)
			(layer "F.Fab")
		)
		(fp_line
			(start -0.8636 0.4572)
			(end -0.8636 0.4318)
			(stroke
				(width 0.1)
				(type default)
			)
			(layer "F.Fab")
		)
		(fp_line
			(start 0.8636 -0.4572)
			(end 0.8636 -0.406654)
			(stroke
				(width 0.1)
				(type default)
			)
			(layer "F.Fab")
		)
		(fp_line
			(start 0.8636 -0.406654)
			(end 1.1938 -0.406654)
			(stroke
				(width 0.1)
				(type default)
			)
			(layer "F.Fab")
		)
		(fp_line
			(start 0.8636 0.4064)
			(end 0.8636 0.4572)
			(stroke
				(width 0.1)
				(type default)
			)
			(layer "F.Fab")
		)
		(fp_line
			(start 0.8636 0.4572)
			(end -0.8636 0.4572)
			(stroke
				(width 0.1)
				(type default)
			)
			(layer "F.Fab")
		)
		(fp_line
			(start 1.1938 -0.406654)
			(end 1.1938 0.4064)
			(stroke
				(width 0.1)
				(type default)
			)
			(layer "F.Fab")
		)
		(fp_line
			(start 1.1938 0.4064)
			(end 0.8636 0.4064)
			(stroke
				(width 0.1)
				(type default)
			)
			(layer "F.Fab")
		)
		(pad "1" smd rect
			(at -0.7366 0 270)
			(size 0.7112 0.8128)
			(layers "F.Cu" "F.Mask" "F.Paste")
			(net "P0V9_CPU0_RT_2D")
		)
		(pad "2" smd rect
			(at 0.7366 0 270)
			(size 0.7112 0.8128)
			(layers "F.Cu" "F.Mask" "F.Paste")
			(net "P0V9_CPU0_RT0_2A_2D")
		)
	)
	(footprint ""
		(layer "F.Cu")
		(at 308.412896 -378.95403 -90)
		(property "Reference" "C920"
			(at 0 0 270)
			(layer "F.SilkS")
			(hide yes)
			(effects
				(font
					(size 1.27 1.27)
				)
			)
		)
		(property "Value" ""
			(at 0 0 270)
			(layer "F.Fab")
			(effects
				(font
					(size 1.27 1.27)
				)
			)
		)
		(duplicate_pad_numbers_are_jumpers no)
		(fp_line
			(start -0.299974 0.150114)
			(end -0.299974 -0.150114)
			(stroke
				(width 0.1)
				(type default)
			)
			(layer "F.Fab")
		)
		(fp_line
			(start 0.299974 0.150114)
			(end -0.299974 0.150114)
			(stroke
				(width 0.1)
				(type default)
			)
			(layer "F.Fab")
		)
		(fp_line
			(start -0.299974 -0.150114)
			(end 0.299974 -0.150114)
			(stroke
				(width 0.1)
				(type default)
			)
			(layer "F.Fab")
		)
		(fp_line
			(start 0.299974 -0.150114)
			(end 0.299974 0.150114)
			(stroke
				(width 0.1)
				(type default)
			)
			(layer "F.Fab")
		)
		(pad "1" smd rect
			(at -0.2667 0 270)
			(size 0.3048 0.381)
			(layers "F.Cu" "F.Mask" "F.Paste")
			(net "P5E_CPU0_P0_TX_C_DN<6>")
		)
		(pad "2" smd rect
			(at 0.2667 0 270)
			(size 0.3048 0.381)
			(layers "F.Cu" "F.Mask" "F.Paste")
			(net "P5E_CPU0_P0_TX_DN<6>")
		)
	)
	(footprint ""
		(layer "F.Cu")
		(at 105.960164 -257.455416)
		(property "Reference" "C2270"
			(at 0 0 0)
			(layer "F.SilkS")
			(hide yes)
			(effects
				(font
					(size 1.27 1.27)
				)
			)
		)
		(property "Value" ""
			(at 0 0 0)
			(layer "F.Fab")
			(effects
				(font
					(size 1.27 1.27)
				)
			)
		)
		(duplicate_pad_numbers_are_jumpers no)
		(fp_line
			(start -0.7874 -0.4064)
			(end 0.7874 -0.4064)
			(stroke
				(width 0.1524)
				(type default)
			)
			(layer "F.SilkS")
		)
		(fp_line
			(start -0.7874 0.4064)
			(end -0.7874 -0.4064)
			(stroke
				(width 0.1524)
				(type default)
			)
			(layer "F.SilkS")
		)
		(fp_line
			(start 0.7874 -0.4064)
			(end 0.7874 0.4064)
			(stroke
				(width 0.1524)
				(type default)
			)
			(layer "F.SilkS")
		)
		(fp_line
			(start 0.7874 0.4064)
			(end -0.7874 0.4064)
			(stroke
				(width 0.1524)
				(type default)
			)
			(layer "F.SilkS")
		)
		(fp_line
			(start -0.67945 -0.305054)
			(end -0.12065 -0.305054)
			(stroke
				(width 0.1)
				(type default)
			)
			(layer "F.Fab")
		)
		(fp_line
			(start -0.67945 0.3048)
			(end -0.67945 -0.305054)
			(stroke
				(width 0.1)
				(type default)
			)
			(layer "F.Fab")
		)
		(fp_line
			(start -0.12065 -0.305054)
			(end -0.12065 -0.2794)
			(stroke
				(width 0.1)
				(type default)
			)
			(layer "F.Fab")
		)
		(fp_line
			(start -0.12065 -0.2794)
			(end 0.12065 -0.2794)
			(stroke
				(width 0.1)
				(type default)
			)
			(layer "F.Fab")
		)
		(fp_line
			(start -0.12065 0.2794)
			(end -0.12065 0.3048)
			(stroke
				(width 0.1)
				(type default)
			)
			(layer "F.Fab")
		)
		(fp_line
			(start -0.12065 0.3048)
			(end -0.67945 0.3048)
			(stroke
				(width 0.1)
				(type default)
			)
			(layer "F.Fab")
		)
		(fp_line
			(start 0.120396 0.2794)
			(end -0.12065 0.2794)
			(stroke
				(width 0.1)
				(type default)
			)
			(layer "F.Fab")
		)
		(fp_line
			(start 0.120396 0.3048)
			(end 0.120396 0.2794)
			(stroke
				(width 0.1)
				(type default)
			)
			(layer "F.Fab")
		)
		(fp_line
			(start 0.12065 -0.3048)
			(end 0.67945 -0.3048)
			(stroke
				(width 0.1)
				(type default)
			)
			(layer "F.Fab")
		)
		(fp_line
			(start 0.12065 -0.2794)
			(end 0.12065 -0.3048)
			(stroke
				(width 0.1)
				(type default)
			)
			(layer "F.Fab")
		)
		(fp_line
			(start 0.67945 -0.3048)
			(end 0.67945 0.3048)
			(stroke
				(width 0.1)
				(type default)
			)
			(layer "F.Fab")
		)
		(fp_line
			(start 0.67945 0.3048)
			(end 0.120396 0.3048)
			(stroke
				(width 0.1)
				(type default)
			)
			(layer "F.Fab")
		)
		(pad "1" smd circle
			(at -0.40005 0)
			(size 0 0)
			(layers "F.Cu" "F.Mask" "F.Paste")
			(net "PVDDIO_P1")
		)
		(pad "2" smd circle
			(at 0.40005 0)
			(size 0 0)
			(layers "F.Cu" "F.Mask" "F.Paste")
			(net "GND")
		)
	)
)
